# BASEBOARD_FAB2 (Tioga Pass) — schematic netlist excerpt (pin names and nets, part order shuffled) for the footprints in the layout excerpt that follows; sources: Cadence DE-HDL packaged netlist, KiCad conversion of Wiwynn_Tioga_Pass_MB.brd

C7C11  CAP_A  0.1UF 16V 10% X7R  pkg 0402V  page 212 : A = VR_FET_SW_P12V_STBY_PVCCIO_CPU0 ; B = GND
C5A10  CAP  100UF 4V 20% X5R  pkg 0805  page 220 : A = PVDDQ_DEF ; B = GND
R8C17  RES  1.00K 1% EMPTY  pkg 0402  page 125 : A = PU_PCH_TLS_ENABLE_STRAP ; B = GND

(kicad_pcb
	(version 20260206)
	(generator "pcbnew")
	(generator_version "10.0")
	(general
		(thickness 1.6)
		(legacy_teardrops no)
	)
	(paper "A4")
	(title_block
		(title "Wiwynn_Tioga_Pass_MB.brd")
		(comment 1 "Tioga Pass / footprints 1834-1836 of 4770")
	)
	(layers
		(0 "F.Cu" signal "TOP")
		(4 "In1.Cu" signal "L2GND")
		(6 "In2.Cu" signal "L3")
		(8 "In3.Cu" signal "L4GND")
		(10 "In4.Cu" signal "L5")
		(12 "In5.Cu" signal "L6GND")
		(14 "In6.Cu" signal "L7VCC")
		(16 "In7.Cu" signal "L8VCC")
		(18 "In8.Cu" signal "L9GND")
		(20 "In9.Cu" signal "L10")
		(22 "In10.Cu" signal "L11GND")
		(24 "In11.Cu" signal "L12")
		(26 "In12.Cu" signal "L13GND")
		(2 "B.Cu" signal "BOTTOM")
		(9 "F.Adhes" user "F.Adhesive")
		(11 "B.Adhes" user "B.Adhesive")
		(13 "F.Paste" user "Package Geometry/Pastemask Top")
		(15 "B.Paste" user "Package Geometry/Pastemask Bottom")
		(5 "F.SilkS" user "Ref Des/Silkscreen Top")
		(7 "B.SilkS" user "Ref Des/Silkscreen Bottom")
		(1 "F.Mask" user "Board Geometry/Soldermask Top")
		(3 "B.Mask" user "Board Geometry/Soldermask Bottom")
		(17 "Dwgs.User" user "User.Drawings")
		(19 "Cmts.User" user "User.Comments")
		(21 "Eco1.User" user "User.Eco1")
		(23 "Eco2.User" user "User.Eco2")
		(25 "Edge.Cuts" user "Board Geometry/Outline")
		(27 "Margin" user)
		(31 "F.CrtYd" user "Package Geometry/Place Bound Top")
		(29 "B.CrtYd" user "Package Geometry/Place Bound Bottom")
		(35 "F.Fab" user "Ref Des/Assembly Top")
		(33 "B.Fab" user "Ref Des/Assembly Bottom")
	)
	(footprint ""
		(layer "F.Cu")
		(at 347.599 -93.761306 -90)
		(property "Reference" "C7C11"
			(at 0 0 270)
			(layer "F.SilkS")
			(hide yes)
			(effects
				(font
					(size 1.27 1.27)
				)
			)
		)
		(property "Value" ""
			(at 0 0 270)
			(layer "F.Fab")
			(effects
				(font
					(size 1.27 1.27)
				)
			)
		)
		(duplicate_pad_numbers_are_jumpers no)
		(fp_poly
			(pts
				(xy 0.3048 -0.1016) (xy 0.3048 0.9906) (xy -0.3048 0.9906) (xy -0.3048 -0.1016)
			)
			(stroke
				(width 0)
				(type default)
			)
			(fill no)
			(layer "F.CrtYd")
		)
		(fp_line
			(start -0.3048 0.9906)
			(end 0.3048 0.9906)
			(stroke
				(width 0.1)
				(type default)
			)
			(layer "F.Fab")
		)
		(fp_line
			(start 0.3048 0.9906)
			(end 0.3048 -0.1016)
			(stroke
				(width 0.1)
				(type default)
			)
			(layer "F.Fab")
		)
		(fp_line
			(start -0.3048 -0.1016)
			(end -0.3048 0.9906)
			(stroke
				(width 0.1)
				(type default)
			)
			(layer "F.Fab")
		)
		(fp_line
			(start 0.3048 -0.1016)
			(end -0.3048 -0.1016)
			(stroke
				(width 0.1)
				(type default)
			)
			(layer "F.Fab")
		)
		(pad "1" smd rect
			(at 0 0 270)
			(size 0.508 0.508)
			(layers "F.Cu" "F.Mask" "F.Paste")
			(net "VR_FET_SW_P12V_STBY_PVCCIO_CPU0")
		)
		(pad "2" smd rect
			(at 0 0.889 270)
			(size 0.508 0.508)
			(layers "F.Cu" "F.Mask" "F.Paste")
			(net "GND")
		)
		(zone
			(layer "F.Cu")
			(hatch none 0.5)
			(connect_pads
				(clearance 0)
			)
			(min_thickness 0.25)
			(keepout
				(tracks not_allowed)
				(vias allowed)
				(pads allowed)
				(copperpour not_allowed)
				(footprints allowed)
			)
			(placement
				(enabled no)
				(sheetname "")
			)
			(fill
				(thermal_gap 0.5)
				(thermal_bridge_width 0.5)
				(island_removal_mode 0)
			)
			(polygon
				(pts
					(xy 346.964 -94.015306) (xy 346.964 -93.507306) (xy 347.345 -93.507306) (xy 347.345 -94.015306)
				)
			)
		)
		(zone
			(layer "F.Cu")
			(hatch none 0.5)
			(connect_pads
				(clearance 0)
			)
			(min_thickness 0.25)
			(keepout
				(tracks allowed)
				(vias not_allowed)
				(pads allowed)
				(copperpour not_allowed)
				(footprints allowed)
			)
			(placement
				(enabled no)
				(sheetname "")
			)
			(fill
				(thermal_gap 0.5)
				(thermal_bridge_width 0.5)
				(island_removal_mode 0)
			)
			(polygon
				(pts
					(xy 347.345 -94.015306) (xy 347.345 -93.507306) (xy 346.964 -93.507306) (xy 346.964 -94.015306)
				)
			)
		)
	)
	(footprint ""
		(layer "F.Cu")
		(at 408.8765 -105.664 -90)
		(property "Reference" "R8C17"
			(at 0 0 270)
			(layer "F.SilkS")
			(hide yes)
			(effects
				(font
					(size 1.27 1.27)
				)
			)
		)
		(property "Value" ""
			(at 0 0 270)
			(layer "F.Fab")
			(effects
				(font
					(size 1.27 1.27)
				)
			)
		)
		(duplicate_pad_numbers_are_jumpers no)
		(fp_poly
			(pts
				(xy -0.2794 -0.1016) (xy 0.2794 -0.1016) (xy 0.2794 0.9906) (xy -0.2794 0.9906)
			)
			(stroke
				(width 0)
				(type default)
			)
			(fill no)
			(layer "F.CrtYd")
		)
		(fp_line
			(start -0.2794 0.9906)
			(end 0.2794 0.9906)
			(stroke
				(width 0.1)
				(type default)
			)
			(layer "F.Fab")
		)
		(fp_line
			(start 0.2794 0.9906)
			(end 0.2794 -0.1016)
			(stroke
				(width 0.1)
				(type default)
			)
			(layer "F.Fab")
		)
		(fp_line
			(start -0.2794 -0.1016)
			(end -0.2794 0.9906)
			(stroke
				(width 0.1)
				(type default)
			)
			(layer "F.Fab")
		)
		(fp_line
			(start 0.2794 -0.1016)
			(end -0.2794 -0.1016)
			(stroke
				(width 0.1)
				(type default)
			)
			(layer "F.Fab")
		)
		(pad "1" smd rect
			(at 0 0 270)
			(size 0.508 0.508)
			(layers "F.Cu" "F.Mask" "F.Paste")
			(net "PU_PCH_TLS_ENABLE_STRAP")
		)
		(pad "2" smd rect
			(at 0 0.889 270)
			(size 0.508 0.508)
			(layers "F.Cu" "F.Mask" "F.Paste")
			(net "GND")
		)
		(zone
			(layer "F.Cu")
			(hatch none 0.5)
			(connect_pads
				(clearance 0)
			)
			(min_thickness 0.25)
			(keepout
				(tracks not_allowed)
				(vias allowed)
				(pads allowed)
				(copperpour not_allowed)
				(footprints allowed)
			)
			(placement
				(enabled no)
				(sheetname "")
			)
			(fill
				(thermal_gap 0.5)
				(thermal_bridge_width 0.5)
				(island_removal_mode 0)
			)
			(polygon
				(pts
					(xy 408.2415 -105.918) (xy 408.2415 -105.41) (xy 408.6225 -105.41) (xy 408.6225 -105.918)
				)
			)
		)
		(zone
			(layer "F.Cu")
			(hatch none 0.5)
			(connect_pads
				(clearance 0)
			)
			(min_thickness 0.25)
			(keepout
				(tracks allowed)
				(vias not_allowed)
				(pads allowed)
				(copperpour not_allowed)
				(footprints allowed)
			)
			(placement
				(enabled no)
				(sheetname "")
			)
			(fill
				(thermal_gap 0.5)
				(thermal_bridge_width 0.5)
				(island_removal_mode 0)
			)
			(polygon
				(pts
					(xy 408.6225 -105.918) (xy 408.6225 -105.41) (xy 408.2415 -105.41) (xy 408.2415 -105.918)
				)
			)
		)
	)
	(footprint ""
		(layer "F.Cu")
		(at 259.1054 -149.7838 90)
		(property "Reference" "C5A10"
			(at 0 0 90)
			(layer "F.SilkS")
			(hide yes)
			(effects
				(font
					(size 1.27 1.27)
				)
			)
		)
		(property "Value" ""
			(at 0 0 90)
			(layer "F.Fab")
			(effects
				(font
					(size 1.27 1.27)
				)
			)
		)
		(duplicate_pad_numbers_are_jumpers no)
		(fp_rect
			(start -0.7239 -0.2159)
			(end 0.7239 1.9939)
			(stroke
				(width 0)
				(type default)
			)
			(fill no)
			(layer "F.CrtYd")
		)
		(fp_line
			(start 0.7239 -0.2159)
			(end -0.7239 -0.2159)
			(stroke
				(width 0.1)
				(type default)
			)
			(layer "F.Fab")
		)
		(fp_line
			(start -0.7239 -0.2159)
			(end -0.7239 1.9939)
			(stroke
				(width 0.1)
				(type default)
			)
			(layer "F.Fab")
		)
		(fp_line
			(start 0.7239 1.9939)
			(end 0.7239 -0.2159)
			(stroke
				(width 0.1)
				(type default)
			)
			(layer "F.Fab")
		)
		(fp_line
			(start -0.7239 1.9939)
			(end 0.7239 1.9939)
			(stroke
				(width 0.1)
				(type default)
			)
			(layer "F.Fab")
		)
		(pad "1" smd rect
			(at 0 0 90)
			(size 1.27 1.016)
			(layers "F.Cu" "F.Mask" "F.Paste")
			(net "PVDDQ_DEF")
		)
		(pad "2" smd rect
			(at 0 1.778 90)
			(size 1.27 1.016)
			(layers "F.Cu" "F.Mask" "F.Paste")
			(net "GND")
		)
		(zone
			(layer "F.Cu")
			(hatch none 0.5)
			(connect_pads
				(clearance 0)
			)
			(min_thickness 0.25)
			(keepout
				(tracks not_allowed)
				(vias allowed)
				(pads allowed)
				(copperpour not_allowed)
				(footprints allowed)
			)
			(placement
				(enabled no)
				(sheetname "")
			)
			(fill
				(thermal_gap 0.5)
				(thermal_bridge_width 0.5)
				(island_removal_mode 0)
			)
			(polygon
				(pts
					(xy 259.6134 -149.1488) (xy 260.3754 -149.1488) (xy 260.3754 -150.4188) (xy 259.6134 -150.4188)
				)
			)
		)
	)
)
